(kicad_pcb
	(version 20260206)
	(generator "pcbnew")
	(generator_version "10.0")
	(general
		(thickness 1.6)
		(legacy_teardrops no)
	)
	(paper "A4")
	(title_block
		(title "12092022_DA0F0TFB6D0_F0T_FAN_BOARD_MP5048_D_brd_v02_OCP.brd")
		(comment 1 "Grand Teton / footprints 911-914 of 924")
	)
	(layers
		(0 "F.Cu" signal "TOP")
		(4 "In1.Cu" signal "GND")
		(6 "In2.Cu" signal "IN1")
		(8 "In3.Cu" signal "IN2")
		(10 "In4.Cu" signal "GND1")
		(2 "B.Cu" signal "BOTTOM")
		(9 "F.Adhes" user "F.Adhesive")
		(11 "B.Adhes" user "B.Adhesive")
		(13 "F.Paste" user "Package Geometry/Pastemask Top")
		(15 "B.Paste" user "Package Geometry/Pastemask Bottom")
		(5 "F.SilkS" user "Ref Des/Silkscreen Top")
		(7 "B.SilkS" user "Ref Des/Silkscreen Bottom")
		(1 "F.Mask" user "Board Geometry/Soldermask Top")
		(3 "B.Mask" user "Board Geometry/Soldermask Bottom")
		(17 "Dwgs.User" user "User.Drawings")
		(19 "Cmts.User" user "User.Comments")
		(21 "Eco1.User" user "User.Eco1")
		(23 "Eco2.User" user "User.Eco2")
		(25 "Edge.Cuts" user "Board Geometry/Outline")
		(27 "Margin" user)
		(31 "F.CrtYd" user "Package Geometry/Place Bound Top")
		(29 "B.CrtYd" user "Package Geometry/Place Bound Bottom")
		(35 "F.Fab" user "Ref Des/Assembly Top")
		(33 "B.Fab" user "Ref Des/Assembly Bottom")
	)
	(footprint ""
		(layer "B.Cu")
		(at 7.326376 -41.383712 180)
		(property "Reference" "PD7"
			(at 2.678176 -3.767582 0)
			(unlocked yes)
			(layer "B.SilkS")
			(effects
				(font
					(size 0.7874 0.5842)
					(thickness 0.1524)
				)
				(justify left mirror)
			)
		)
		(property "Value" ""
			(at 0 0 0)
			(layer "B.Fab")
			(effects
				(font
					(size 1.27 1.27)
				)
				(justify mirror)
			)
		)
		(duplicate_pad_numbers_are_jumpers no)
		(fp_line
			(start 4.826 3.109976)
			(end 4.826 0)
			(stroke
				(width 0.1524)
				(type default)
			)
			(layer "B.SilkS")
		)
		(fp_line
			(start 4.826 0)
			(end 4.826 -3.109976)
			(stroke
				(width 0.1524)
				(type default)
			)
			(layer "B.SilkS")
		)
		(fp_line
			(start 4.826 -3.109976)
			(end -4.826 -3.109976)
			(stroke
				(width 0.1524)
				(type default)
			)
			(layer "B.SilkS")
		)
		(fp_line
			(start 1.0922 0)
			(end 1.7018 0)
			(stroke
				(width 0.1524)
				(type default)
			)
			(layer "B.SilkS")
		)
		(fp_line
			(start 1.016 1.016)
			(end -1.016 0)
			(stroke
				(width 0.1524)
				(type default)
			)
			(layer "B.SilkS")
		)
		(fp_line
			(start 1.016 -1.016)
			(end 1.016 1.016)
			(stroke
				(width 0.1524)
				(type default)
			)
			(layer "B.SilkS")
		)
		(fp_line
			(start -1.143 1.397)
			(end -1.143 -1.397)
			(stroke
				(width 0.1524)
				(type default)
			)
			(layer "B.SilkS")
		)
		(fp_line
			(start -1.143 0)
			(end 1.016 -1.016)
			(stroke
				(width 0.1524)
				(type default)
			)
			(layer "B.SilkS")
		)
		(fp_line
			(start -1.143 0)
			(end -1.8034 0)
			(stroke
				(width 0.1524)
				(type default)
			)
			(layer "B.SilkS")
		)
		(fp_line
			(start -4.8133 -3.109976)
			(end -5.3467 -3.109976)
			(stroke
				(width 0.1524)
				(type default)
			)
			(layer "B.SilkS")
		)
		(fp_line
			(start -4.826 3.109976)
			(end 4.826 3.109976)
			(stroke
				(width 0.1524)
				(type default)
			)
			(layer "B.SilkS")
		)
		(fp_line
			(start -4.826 0)
			(end -4.826 3.109976)
			(stroke
				(width 0.1524)
				(type default)
			)
			(layer "B.SilkS")
		)
		(fp_line
			(start -4.826 -3.109976)
			(end -4.826 0)
			(stroke
				(width 0.1524)
				(type default)
			)
			(layer "B.SilkS")
		)
		(fp_line
			(start -4.9276 3.109976)
			(end -4.9276 -3.109976)
			(stroke
				(width 0.1524)
				(type default)
			)
			(layer "B.SilkS")
		)
		(fp_line
			(start -5.0292 3.109976)
			(end -5.0292 -3.109976)
			(stroke
				(width 0.1524)
				(type default)
			)
			(layer "B.SilkS")
		)
		(fp_line
			(start -5.1308 3.109976)
			(end -5.1308 -3.109976)
			(stroke
				(width 0.1524)
				(type default)
			)
			(layer "B.SilkS")
		)
		(fp_line
			(start -5.207 3.109976)
			(end -5.207 -3.109976)
			(stroke
				(width 0.1524)
				(type default)
			)
			(layer "B.SilkS")
		)
		(fp_line
			(start -5.334 3.109976)
			(end -4.8133 3.109976)
			(stroke
				(width 0.1524)
				(type default)
			)
			(layer "B.SilkS")
		)
		(fp_line
			(start -5.334 3.109976)
			(end -5.334 0)
			(stroke
				(width 0.1524)
				(type default)
			)
			(layer "B.SilkS")
		)
		(fp_line
			(start -5.334 0)
			(end -5.334 -3.109976)
			(stroke
				(width 0.1524)
				(type default)
			)
			(layer "B.SilkS")
		)
		(fp_line
			(start 3.554984 3.109976)
			(end 3.554984 -3.109976)
			(stroke
				(width 0.1)
				(type default)
			)
			(layer "B.Fab")
		)
		(fp_line
			(start 3.554984 -3.109976)
			(end -3.554984 -3.109976)
			(stroke
				(width 0.1)
				(type default)
			)
			(layer "B.Fab")
		)
		(fp_line
			(start 1.0922 0)
			(end 1.7018 0)
			(stroke
				(width 0.1)
				(type default)
			)
			(layer "B.Fab")
		)
		(fp_line
			(start 1.016 1.016)
			(end -1.016 0)
			(stroke
				(width 0.1)
				(type default)
			)
			(layer "B.Fab")
		)
		(fp_line
			(start 1.016 -1.016)
			(end 1.016 1.016)
			(stroke
				(width 0.1)
				(type default)
			)
			(layer "B.Fab")
		)
		(fp_line
			(start -1.143 1.397)
			(end -1.143 -1.397)
			(stroke
				(width 0.1)
				(type default)
			)
			(layer "B.Fab")
		)
		(fp_line
			(start -1.143 0)
			(end 1.016 -1.016)
			(stroke
				(width 0.1)
				(type default)
			)
			(layer "B.Fab")
		)
		(fp_line
			(start -1.143 0)
			(end -1.8034 0)
			(stroke
				(width 0.1)
				(type default)
			)
			(layer "B.Fab")
		)
		(fp_line
			(start -3.554984 3.109976)
			(end 3.554984 3.109976)
			(stroke
				(width 0.1)
				(type default)
			)
			(layer "B.Fab")
		)
		(fp_line
			(start -3.554984 -3.109976)
			(end -3.554984 3.109976)
			(stroke
				(width 0.1)
				(type default)
			)
			(layer "B.Fab")
		)
		(fp_text user "+"
			(at 5.040376 -0.013462 0)
			(unlocked yes)
			(layer "B.SilkS")
			(effects
				(font
					(size 1.905 1.4224)
					(thickness 0.1524)
				)
				(justify left mirror)
			)
		)
		(fp_text user "-"
			(at -6.6802 0.22225 0)
			(unlocked yes)
			(layer "B.SilkS")
			(effects
				(font
					(size 1.905 1.4224)
					(thickness 0.1524)
				)
				(justify left mirror)
			)
		)
		(fp_text user "+"
			(at 4.5466 0.19685 0)
			(unlocked yes)
			(layer "B.Fab")
			(effects
				(font
					(size 1.905 1.4224)
					(thickness 0.1524)
				)
				(justify left mirror)
			)
		)
		(fp_text user "-"
			(at -6.6802 0.22225 0)
			(unlocked yes)
			(layer "B.Fab")
			(effects
				(font
					(size 1.905 1.4224)
					(thickness 0.1524)
				)
				(justify left mirror)
			)
		)
		(pad "A" smd rect
			(at 3.400044 0 180)
			(size 2.5146 3.302)
			(layers "B.Cu" "B.Mask" "B.Paste")
			(net "GND")
		)
		(pad "C" smd rect
			(at -3.400044 0 180)
			(size 2.5146 3.302)
			(layers "B.Cu" "B.Mask" "B.Paste")
			(net "P52V_FAN_4")
		)
	)
	(footprint ""
		(layer "B.Cu")
		(at 44.99991 -303.310036)
		(property "Reference" "J1"
			(at 3.64109 -5.273294 0)
			(unlocked yes)
			(layer "B.SilkS")
			(effects
				(font
					(size 0.7874 0.5842)
					(thickness 0.1524)
				)
				(justify left mirror)
			)
		)
		(property "Value" ""
			(at 0 0 0)
			(layer "B.Fab")
			(effects
				(font
					(size 1.27 1.27)
				)
				(justify mirror)
			)
		)
		(duplicate_pad_numbers_are_jumpers no)
		(fp_line
			(start -6.35 -4.52501)
			(end 4.350004 -4.52501)
			(stroke
				(width 0.1524)
				(type default)
			)
			(layer "B.SilkS")
		)
		(fp_line
			(start -6.35 18.524982)
			(end -6.35 -4.52501)
			(stroke
				(width 0.1524)
				(type default)
			)
			(layer "B.SilkS")
		)
		(fp_line
			(start -3.24993 -1.42494)
			(end -1.96977 -1.42494)
			(stroke
				(width 0.1524)
				(type default)
			)
			(layer "B.SilkS")
		)
		(fp_line
			(start -3.24993 15.424912)
			(end -3.24993 -1.42494)
			(stroke
				(width 0.1524)
				(type default)
			)
			(layer "B.SilkS")
		)
		(fp_line
			(start -0.029972 -1.42494)
			(end 1.249934 -1.42494)
			(stroke
				(width 0.1524)
				(type default)
			)
			(layer "B.SilkS")
		)
		(fp_line
			(start 1.249934 -1.42494)
			(end 1.249934 5.799836)
			(stroke
				(width 0.1524)
				(type default)
			)
			(layer "B.SilkS")
		)
		(fp_line
			(start 1.249934 5.799836)
			(end 4.350004 5.799836)
			(stroke
				(width 0.1524)
				(type default)
			)
			(layer "B.SilkS")
		)
		(fp_line
			(start 1.249934 8.200136)
			(end 1.249934 15.424912)
			(stroke
				(width 0.1524)
				(type default)
			)
			(layer "B.SilkS")
		)
		(fp_line
			(start 1.249934 8.200136)
			(end 4.350004 8.200136)
			(stroke
				(width 0.1524)
				(type default)
			)
			(layer "B.SilkS")
		)
		(fp_line
			(start 1.249934 15.424912)
			(end -3.24993 15.424912)
			(stroke
				(width 0.1524)
				(type default)
			)
			(layer "B.SilkS")
		)
		(fp_line
			(start 4.350004 -4.52501)
			(end 4.350004 18.524982)
			(stroke
				(width 0.1524)
				(type default)
			)
			(layer "B.SilkS")
		)
		(fp_line
			(start 4.350004 18.524982)
			(end -6.35 18.524982)
			(stroke
				(width 0.1524)
				(type default)
			)
			(layer "B.SilkS")
		)
		(fp_poly
			(pts
				(xy 5.527802 -0.508) (xy 5.527802 0.508) (xy 4.511802 0)
			)
			(stroke
				(width 0)
				(type default)
			)
			(fill yes)
			(layer "B.SilkS")
		)
		(fp_line
			(start -6.35 -4.52501)
			(end 4.350004 -4.52501)
			(stroke
				(width 0.1)
				(type default)
			)
			(layer "B.Fab")
		)
		(fp_line
			(start -6.35 18.524982)
			(end -6.35 -4.52501)
			(stroke
				(width 0.1)
				(type default)
			)
			(layer "B.Fab")
		)
		(fp_line
			(start 4.350004 -4.52501)
			(end 4.350004 18.524982)
			(stroke
				(width 0.1)
				(type default)
			)
			(layer "B.Fab")
		)
		(fp_line
			(start 4.350004 18.524982)
			(end -6.35 18.524982)
			(stroke
				(width 0.1)
				(type default)
			)
			(layer "B.Fab")
		)
		(fp_poly
			(pts
				(xy 5.527802 -0.508) (xy 5.527802 0.508) (xy 4.511802 0)
			)
			(stroke
				(width 0)
				(type default)
			)
			(fill yes)
			(layer "B.Fab")
		)
		(pad "" np_thru_hole circle
			(at -0.999998 -1.89992 270)
			(size 1.4986 1.4986)
			(drill 1.4986)
			(layers "*.Cu" "*.Mask")
			(clearance 0.381)
			(thermal_gap 0.381)
		)
		(pad "1" thru_hole rect
			(at 0 0 270)
			(size 1.3716 1.3716)
			(drill 0.9652)
			(layers "*.Cu" "*.Mask")
			(remove_unused_layers no)
			(net "FAN_0_TACH_IL_D")
			(clearance 0.0508)
			(padstack
				(mode front_inner_back)
				(layer "Inner"
					(shape circle)
					(size 1.3716 1.3716)
					(clearance 0.0508)
				)
				(layer "B.Cu"
					(shape rect)
					(size 1.3716 1.3716)
					(thermal_gap 0.0508)
					(clearance 0.0508)
				)
			)
		)
		(pad "2" thru_hole circle
			(at -1.999996 0 270)
			(size 1.3716 1.3716)
			(drill 0.9652)
			(layers "*.Cu" "*.Mask")
			(remove_unused_layers no)
			(net "FAN_0_PWM_OL_R")
			(clearance 0.0508)
			(thermal_gap 0.0508)
		)
		(pad "3" thru_hole circle
			(at 0 1.999996 270)
			(size 1.3716 1.3716)
			(drill 0.9652)
			(layers "*.Cu" "*.Mask")
			(remove_unused_layers no)
			(net "FAN_0_PWM_IL_R")
			(clearance 0.0508)
			(thermal_gap 0.0508)
		)
		(pad "4" thru_hole circle
			(at -1.999996 1.999996 270)
			(size 1.3716 1.3716)
			(drill 0.9652)
			(layers "*.Cu" "*.Mask")
			(remove_unused_layers no)
			(net "FAN_0_PRESENT_R_N")
			(clearance 0.0508)
			(thermal_gap 0.0508)
		)
		(pad "5" thru_hole circle
			(at 0 3.999992 270)
			(size 1.3716 1.3716)
			(drill 0.9652)
			(layers "*.Cu" "*.Mask")
			(remove_unused_layers no)
			(net "P12V_LED_R1_FAN0")
			(clearance 0.0508)
			(thermal_gap 0.0508)
		)
		(pad "6" thru_hole circle
			(at -1.999996 3.999992 270)
			(size 1.3716 1.3716)
			(drill 0.9652)
			(layers "*.Cu" "*.Mask")
			(remove_unused_layers no)
			(net "SMB_FAN0_SCL_R")
			(clearance 0.0508)
			(thermal_gap 0.0508)
		)
		(pad "7" thru_hole circle
			(at 0 5.999988 270)
			(size 1.3716 1.3716)
			(drill 0.9652)
			(layers "*.Cu" "*.Mask")
			(remove_unused_layers no)
			(net "SMB_FAN0_SDA_R")
			(clearance 0.0508)
			(thermal_gap 0.0508)
		)
		(pad "8" thru_hole circle
			(at -1.999996 5.999988 270)
			(size 1.3716 1.3716)
			(drill 0.9652)
			(layers "*.Cu" "*.Mask")
			(remove_unused_layers no)
			(net "GND")
			(clearance 0.0508)
			(thermal_gap 0.0508)
		)
		(pad "9" thru_hole circle
			(at 0 7.999984 270)
			(size 1.3716 1.3716)
			(drill 0.9652)
			(layers "*.Cu" "*.Mask")
			(remove_unused_layers no)
			(net "GND")
			(clearance 0.0508)
			(thermal_gap 0.0508)
		)
		(pad "10" thru_hole circle
			(at -1.999996 7.999984 270)
			(size 1.3716 1.3716)
			(drill 0.9652)
			(layers "*.Cu" "*.Mask")
			(remove_unused_layers no)
			(net "P52V_FAN_0")
			(clearance 0.0508)
			(thermal_gap 0.0508)
		)
		(pad "11" thru_hole circle
			(at 0 9.99998 270)
			(size 1.3716 1.3716)
			(drill 0.9652)
			(layers "*.Cu" "*.Mask")
			(remove_unused_layers no)
			(net "P52V_FAN_0")
			(clearance 0.0508)
			(thermal_gap 0.0508)
		)
		(pad "12" thru_hole circle
			(at -1.999996 9.99998 270)
			(size 1.3716 1.3716)
			(drill 0.9652)
			(layers "*.Cu" "*.Mask")
			(remove_unused_layers no)
			(net "FAN_0_FAIL_R_LED_N")
			(clearance 0.0508)
			(thermal_gap 0.0508)
		)
		(pad "13" thru_hole circle
			(at 0 11.999976 270)
			(size 1.3716 1.3716)
			(drill 0.9652)
			(layers "*.Cu" "*.Mask")
			(remove_unused_layers no)
			(net "FAN_0_TACH_OL_D")
			(clearance 0.0508)
			(thermal_gap 0.0508)
		)
		(pad "14" thru_hole circle
			(at -1.999996 11.999976 270)
			(size 1.3716 1.3716)
			(drill 0.9652)
			(layers "*.Cu" "*.Mask")
			(remove_unused_layers no)
			(net "FAN_0_OK_R_LED_N")
			(clearance 0.0508)
			(thermal_gap 0.0508)
		)
		(pad "15" thru_hole circle
			(at 0 13.999972 270)
			(size 1.3716 1.3716)
			(drill 0.9652)
			(layers "*.Cu" "*.Mask")
			(remove_unused_layers no)
			(net "Net_618")
			(clearance 0.0508)
			(thermal_gap 0.0508)
		)
		(pad "16" thru_hole circle
			(at -1.999996 13.999972 270)
			(size 1.3716 1.3716)
			(drill 0.9652)
			(layers "*.Cu" "*.Mask")
			(remove_unused_layers no)
			(net "Net_617")
			(clearance 0.0508)
			(thermal_gap 0.0508)
		)
		(zone
			(layers "F.Cu" "B.Cu" "In1.Cu" "In2.Cu" "In3.Cu" "In4.Cu")
			(hatch none 0.5)
			(connect_pads
				(clearance 0)
			)
			(min_thickness 0.25)
			(keepout
				(tracks not_allowed)
				(vias allowed)
				(pads allowed)
				(copperpour not_allowed)
				(footprints allowed)
			)
			(placement
				(enabled no)
				(sheetname "")
			)
			(fill
				(thermal_gap 0.5)
				(thermal_bridge_width 0.5)
				(island_removal_mode 0)
			)
			(polygon
				(pts
					(arc
						(start 45.257212 -305.209956)
						(mid 42.742612 -305.209956)
						(end 45.257212 -305.209956)
					)
				)
			)
		)
	)
	(footprint ""
		(layer "B.Cu")
		(at 40.11168 -250.23699 -90)
		(property "Reference" "PC26"
			(at 0 0 90)
			(layer "B.SilkS")
			(hide yes)
			(effects
				(font
					(size 1.27 1.27)
				)
				(justify mirror)
			)
		)
		(property "Value" ""
			(at 0 0 90)
			(layer "B.Fab")
			(effects
				(font
					(size 1.27 1.27)
				)
				(justify mirror)
			)
		)
		(duplicate_pad_numbers_are_jumpers no)
		(fp_line
			(start -0.7874 0.4064)
			(end 0.7874 0.4064)
			(stroke
				(width 0.1524)
				(type default)
			)
			(layer "B.SilkS")
		)
		(fp_line
			(start 0.7874 0.4064)
			(end 0.7874 -0.4064)
			(stroke
				(width 0.1524)
				(type default)
			)
			(layer "B.SilkS")
		)
		(fp_line
			(start -0.7874 -0.4064)
			(end -0.7874 0.4064)
			(stroke
				(width 0.1524)
				(type default)
			)
			(layer "B.SilkS")
		)
		(fp_line
			(start 0.7874 -0.4064)
			(end -0.7874 -0.4064)
			(stroke
				(width 0.1524)
				(type default)
			)
			(layer "B.SilkS")
		)
		(fp_line
			(start -0.67945 0.3048)
			(end -0.120396 0.3048)
			(stroke
				(width 0.1)
				(type default)
			)
			(layer "B.Fab")
		)
		(fp_line
			(start -0.120396 0.3048)
			(end -0.120396 0.2794)
			(stroke
				(width 0.1)
				(type default)
			)
			(layer "B.Fab")
		)
		(fp_line
			(start 0.12065 0.3048)
			(end 0.67945 0.3048)
			(stroke
				(width 0.1)
				(type default)
			)
			(layer "B.Fab")
		)
		(fp_line
			(start 0.67945 0.3048)
			(end 0.67945 -0.305054)
			(stroke
				(width 0.1)
				(type default)
			)
			(layer "B.Fab")
		)
		(fp_line
			(start -0.120396 0.2794)
			(end 0.12065 0.2794)
			(stroke
				(width 0.1)
				(type default)
			)
			(layer "B.Fab")
		)
		(fp_line
			(start 0.12065 0.2794)
			(end 0.12065 0.3048)
			(stroke
				(width 0.1)
				(type default)
			)
			(layer "B.Fab")
		)
		(fp_line
			(start -0.12065 -0.2794)
			(end -0.12065 -0.3048)
			(stroke
				(width 0.1)
				(type default)
			)
			(layer "B.Fab")
		)
		(fp_line
			(start 0.12065 -0.2794)
			(end -0.12065 -0.2794)
			(stroke
				(width 0.1)
				(type default)
			)
			(layer "B.Fab")
		)
		(fp_line
			(start -0.67945 -0.3048)
			(end -0.67945 0.3048)
			(stroke
				(width 0.1)
				(type default)
			)
			(layer "B.Fab")
		)
		(fp_line
			(start -0.12065 -0.3048)
			(end -0.67945 -0.3048)
			(stroke
				(width 0.1)
				(type default)
			)
			(layer "B.Fab")
		)
		(fp_line
			(start 0.12065 -0.305054)
			(end 0.12065 -0.2794)
			(stroke
				(width 0.1)
				(type default)
			)
			(layer "B.Fab")
		)
		(fp_line
			(start 0.67945 -0.305054)
			(end 0.12065 -0.305054)
			(stroke
				(width 0.1)
				(type default)
			)
			(layer "B.Fab")
		)
		(pad "1" smd circle
			(at 0.40005 0 90)
			(size 0 0)
			(layers "B.Cu" "B.Mask" "B.Paste")
			(net "FAN_1_P5V")
		)
		(pad "2" smd circle
			(at -0.40005 0 90)
			(size 0 0)
			(layers "B.Cu" "B.Mask" "B.Paste")
			(net "GND")
		)
	)
	(footprint ""
		(layer "B.Cu")
		(at 5.596128 -235.422948)
		(property "Reference" "C2114"
			(at 0 0 0)
			(layer "B.SilkS")
			(hide yes)
			(effects
				(font
					(size 1.27 1.27)
				)
				(justify mirror)
			)
		)
		(property "Value" ""
			(at 0 0 0)
			(layer "B.Fab")
			(effects
				(font
					(size 1.27 1.27)
				)
				(justify mirror)
			)
		)
		(duplicate_pad_numbers_are_jumpers no)
		(fp_line
			(start -2.2098 -0.9398)
			(end -2.2098 0.9398)
			(stroke
				(width 0.1524)
				(type default)
			)
			(layer "B.SilkS")
		)
		(fp_line
			(start -2.2098 0.9398)
			(end 2.2098 0.9398)
			(stroke
				(width 0.1524)
				(type default)
			)
			(layer "B.SilkS")
		)
		(fp_line
			(start 2.2098 -0.9398)
			(end -2.2098 -0.9398)
			(stroke
				(width 0.1524)
				(type default)
			)
			(layer "B.SilkS")
		)
		(fp_line
			(start 2.2098 0.9398)
			(end 2.2098 -0.9398)
			(stroke
				(width 0.1524)
				(type default)
			)
			(layer "B.SilkS")
		)
		(fp_line
			(start -1.700022 -0.899922)
			(end -1.700022 0.899922)
			(stroke
				(width 0.1)
				(type default)
			)
			(layer "B.Fab")
		)
		(fp_line
			(start -1.700022 0.899922)
			(end 1.700022 0.899922)
			(stroke
				(width 0.1)
				(type default)
			)
			(layer "B.Fab")
		)
		(fp_line
			(start 1.700022 -0.899922)
			(end -1.700022 -0.899922)
			(stroke
				(width 0.1)
				(type default)
			)
			(layer "B.Fab")
		)
		(fp_line
			(start 1.700022 0.899922)
			(end 1.700022 -0.899922)
			(stroke
				(width 0.1)
				(type default)
			)
			(layer "B.Fab")
		)
		(pad "1" smd rect
			(at 1.4732 0)
			(size 1.1684 1.5748)
			(layers "B.Cu" "B.Mask" "B.Paste")
			(net "P52V_FAN_6")
		)
		(pad "2" smd rect
			(at -1.4732 0)
			(size 1.1684 1.5748)
			(layers "B.Cu" "B.Mask" "B.Paste")
			(net "GND")
		)
	)
)
